FILE_TYPE = MACRO_DRAWING;
SET COLOR_WIRE YELLOW;
SET COLOR_PROP ORANGE;
SET COLOR_DOT WHITE;
SET COLOR_ARC YELLOW;
SET COLOR_BODY GREEN;
SET COLOR_NOTE PURPLE;
SET PROP_DISPLAY VALUE;
SET PAGE_NUMBER P435;
FORCEADD QUANTA_TITLE_BLOCK_C..1
(0 0);
FORCEPROP 1 LAST CUSTOM_TXT_CDS <NAME_2>
J 0
(-3175 50);
FORCEPROP 1 LAST CUSTOM_TXT_CDS <NAME_1>
J 0
(-3175 175);
FORCEPROP 1 LAST CUSTOM_TXT_CDS <Q_NUMBER>
J 0
(-1403 103);
DISPLAY 1.212766 (-1403 103);
FORCEPROP 1 LAST CUSTOM_TXT_CDS <Q_PROJ>
J 0
(-2382 102);
DISPLAY 1.212766 (-2382 102);
FORCEPROP 1 LAST CUSTOM_TXT_CDS <Q_REV>
J 0
(-184 103);
DISPLAY 1.212766 (-184 103);
FORCEPROP 1 LAST CUSTOM_TXT_CDS <CON_LAST_MODIFIED>
J 0
(-1885 15);
DISPLAY 0.978723 (-1885 15);
FORCEPROP 1 LAST CUSTOM_TXT_CDS <CON_PAGE_NUM> OF <CON_TOTAL_PAGES>
J 0
(-446 18);
DISPLAY 0.978723 (-446 18);
FORCEPROP 1 LAST Q_TITLE RETIMER_CPU0_P3(10)
J 0
(-9366 26);
DISPLAY 2.446809 (-9366 26);
PAINT GREEN (-9366 26);
FORCEPROP 2 LAST CDS_LIB pure_quanta
J 0
(0 0);
DISPLAY INVISIBLE (0 0);
FORCEPROP 1 LAST CDS_LMAN_SYM_OUTLINE -9475,6775,100,-125
J 0
(0 0);
DISPLAY 0.468085 (0 0);
PAINT GREEN (0 0);
DISPLAY INVISIBLE (0 0);
FORCEPROP 2 LAST PAGE_BORDER TRUE
J 0
(-7890 5250);
DISPLAY 0.638298 (-7890 5250);
PAINT PINK (-7890 5250);
DISPLAY INVISIBLE (-7890 5250);
FORCEPROP 2 LAST CDS_XR_PAGE_TITLE CR-315 : @T6G_MB_LIB.T6G(SCH_1):PAGE315
J 0
(-7890 5250);
DISPLAY 0.638298 (-7890 5250);
PAINT PINK (-7890 5250);
DISPLAY INVISIBLE (-7890 5250);
FORCEPROP 2 LAST CUSTOM_TXT_CDS <XR_PAGE_TITLE>
J 0
(-7890 5250);
DISPLAY 0.638298 (-7890 5250);
PAINT PINK (-7890 5250);
DISPLAY INVISIBLE (-7890 5250);
FORCEPROP 1 LAST COMMENT_BODY TRUE
J 0
(12 -13);
DISPLAY 0.978723 (12 -13);
PAINT GREEN (12 -13);
DISPLAY INVISIBLE (12 -13);
FORCEPROP 1 LAST Q_DEPT BU9
J 1
(-3763 49);
DISPLAY 1.957447 (-3763 49);
PAINT GREEN (-3763 49);
DISPLAY INVISIBLE (-3763 49);
FORCEPROP 0 LAST CDS_CON_LAST_MODIFIED Thu Aug 24 10:16:36 2023
J 0
(-1885 15);
DISPLAY INVISIBLE (-1885 15);
QUIT
